# T6G (Grand Teton) — schematic netlist excerpt (pin names and nets, part order shuffled) for the footprints in the layout excerpt that follows; sources: Cadence DE-HDL packaged netlist, KiCad conversion of 04192023_DAF0TMB3IC0_F0TG_MB_C_brd_V02_OCP.brd

C1766  Q_CAP  0.1UF 25V 10% X7R  pkg 0402  page 248 : A = P3V3_AUX ; B = GND

U31  74LVC1G08W57  74LVC1G08W5-7 IC  pkg SOT25-5_0-95_3X1-6  page 142
  A  = P12V_OCP_V3_2_EN_R3
  B  = HP_LVC3_OCP_V3_2_PRSNT2
  GND  = GND
  Y  = P12V_OCP_V3_2_BUF_EN
  VCC  = P3V3_AUX

C898  Q_CAP_DIFFBUS  DIFF BUS_0.22UF 6.3V 20% X6S  pkg C0201  page 64 : \1\ = P5E_CPU0_P3_TX_C_DN<1> ; \2\ = P5E_CPU0_P3_TX_DN<1>

(kicad_pcb
	(version 20260206)
	(generator "pcbnew")
	(generator_version "10.0")
	(general
		(thickness 1.6)
		(legacy_teardrops no)
	)
	(paper "A4")
	(title_block
		(title "04192023_DAF0TMB3IC0_F0TG_MB_C_brd_V02_OCP.brd")
		(comment 1 "Grand Teton / footprints 4931-4933 of 8354")
	)
	(layers
		(0 "F.Cu" signal "TOP")
		(4 "In1.Cu" signal "GND")
		(6 "In2.Cu" signal "IN1")
		(8 "In3.Cu" signal "GND1")
		(10 "In4.Cu" signal "IN2")
		(12 "In5.Cu" signal "GND2")
		(14 "In6.Cu" signal "IN3")
		(16 "In7.Cu" signal "GND3")
		(18 "In8.Cu" signal "VCC")
		(20 "In9.Cu" signal "VCC1")
		(22 "In10.Cu" signal "GND4")
		(24 "In11.Cu" signal "IN4")
		(26 "In12.Cu" signal "GND5")
		(28 "In13.Cu" signal "IN5")
		(30 "In14.Cu" signal "GND6")
		(32 "In15.Cu" signal "IN6")
		(34 "In16.Cu" signal "GND7")
		(2 "B.Cu" signal "BOTTOM")
		(9 "F.Adhes" user "F.Adhesive")
		(11 "B.Adhes" user "B.Adhesive")
		(13 "F.Paste" user "Package Geometry/Pastemask Top")
		(15 "B.Paste" user "Package Geometry/Pastemask Bottom")
		(5 "F.SilkS" user "Ref Des/Silkscreen Top")
		(7 "B.SilkS" user "Ref Des/Silkscreen Bottom")
		(1 "F.Mask" user "Board Geometry/Soldermask Top")
		(3 "B.Mask" user "Board Geometry/Soldermask Bottom")
		(17 "Dwgs.User" user "User.Drawings")
		(19 "Cmts.User" user "User.Comments")
		(21 "Eco1.User" user "User.Eco1")
		(23 "Eco2.User" user "User.Eco2")
		(25 "Edge.Cuts" user "Board Geometry/Outline")
		(27 "Margin" user)
		(31 "F.CrtYd" user "Package Geometry/Place Bound Top")
		(29 "B.CrtYd" user "Package Geometry/Place Bound Bottom")
		(35 "F.Fab" user "Ref Des/Assembly Top")
		(33 "B.Fab" user "Ref Des/Assembly Bottom")
	)
	(footprint ""
		(layer "F.Cu")
		(at 52.705 -38.735)
		(property "Reference" "U31"
			(at -0.882142 -2.608072 0)
			(unlocked yes)
			(layer "F.SilkS")
			(effects
				(font
					(size 0.7874 0.5842)
					(thickness 0.1524)
				)
				(justify left)
			)
		)
		(property "Value" ""
			(at 0 0 0)
			(layer "F.Fab")
			(effects
				(font
					(size 1.27 1.27)
				)
			)
		)
		(duplicate_pad_numbers_are_jumpers no)
		(fp_line
			(start -1.733296 -1.549908)
			(end -1.733296 1.549908)
			(stroke
				(width 0.1524)
				(type default)
			)
			(layer "F.SilkS")
		)
		(fp_line
			(start -1.733296 1.549908)
			(end 1.733296 1.549908)
			(stroke
				(width 0.1524)
				(type default)
			)
			(layer "F.SilkS")
		)
		(fp_line
			(start -0.660908 -1.549908)
			(end -1.733296 -1.549908)
			(stroke
				(width 0.1524)
				(type default)
			)
			(layer "F.SilkS")
		)
		(fp_line
			(start 0 -0.889)
			(end -0.660908 -1.549908)
			(stroke
				(width 0.1524)
				(type default)
			)
			(layer "F.SilkS")
		)
		(fp_line
			(start 0.660908 -1.549908)
			(end 0 -0.889)
			(stroke
				(width 0.1524)
				(type default)
			)
			(layer "F.SilkS")
		)
		(fp_line
			(start 1.733296 -1.549908)
			(end 0.660908 -1.549908)
			(stroke
				(width 0.1524)
				(type default)
			)
			(layer "F.SilkS")
		)
		(fp_line
			(start 1.733296 1.549908)
			(end 1.733296 -1.549908)
			(stroke
				(width 0.1524)
				(type default)
			)
			(layer "F.SilkS")
		)
		(fp_poly
			(pts
				(xy -1.556512 -2.49555) (xy -2.005076 -2.257298) (xy -1.542542 -1.92786)
			)
			(stroke
				(width 0)
				(type default)
			)
			(fill yes)
			(layer "F.SilkS")
		)
		(fp_line
			(start -0.849884 -1.549908)
			(end -0.849884 1.549908)
			(stroke
				(width 0.1)
				(type default)
			)
			(layer "F.Fab")
		)
		(fp_line
			(start -0.849884 1.549908)
			(end 0.849884 1.549908)
			(stroke
				(width 0.1)
				(type default)
			)
			(layer "F.Fab")
		)
		(fp_line
			(start 0.849884 -1.549908)
			(end -0.849884 -1.549908)
			(stroke
				(width 0.1)
				(type default)
			)
			(layer "F.Fab")
		)
		(fp_line
			(start 0.849884 1.549908)
			(end 0.849884 -1.549908)
			(stroke
				(width 0.1)
				(type default)
			)
			(layer "F.Fab")
		)
		(fp_poly
			(pts
				(xy -2.4384 -1.20396) (xy -2.4384 -0.69596) (xy -1.9304 -0.94996)
			)
			(stroke
				(width 0)
				(type default)
			)
			(fill yes)
			(layer "F.Fab")
		)
		(pad "1" smd rect
			(at -1.199896 -0.94996 270)
			(size 0.5588 0.8128)
			(layers "F.Cu" "F.Mask" "F.Paste")
			(net "P12V_OCP_V3_2_EN_R3")
		)
		(pad "2" smd rect
			(at -1.199896 0 270)
			(size 0.5588 0.8128)
			(layers "F.Cu" "F.Mask" "F.Paste")
			(net "HP_LVC3_OCP_V3_2_PRSNT2")
		)
		(pad "3" smd rect
			(at -1.199896 0.94996 270)
			(size 0.5588 0.8128)
			(layers "F.Cu" "F.Mask" "F.Paste")
			(net "GND")
		)
		(pad "4" smd rect
			(at 1.199896 0.94996 270)
			(size 0.5588 0.8128)
			(layers "F.Cu" "F.Mask" "F.Paste")
			(net "P12V_OCP_V3_2_BUF_EN")
		)
		(pad "5" smd rect
			(at 1.199896 -0.94996 270)
			(size 0.5588 0.8128)
			(layers "F.Cu" "F.Mask" "F.Paste")
			(net "P3V3_AUX")
		)
	)
	(footprint ""
		(layer "F.Cu")
		(at 366.06734 -385.23926 180)
		(property "Reference" "C898"
			(at 0 0 180)
			(layer "F.SilkS")
			(hide yes)
			(effects
				(font
					(size 1.27 1.27)
				)
			)
		)
		(property "Value" ""
			(at 0 0 180)
			(layer "F.Fab")
			(effects
				(font
					(size 1.27 1.27)
				)
			)
		)
		(duplicate_pad_numbers_are_jumpers no)
		(fp_line
			(start 0.299974 0.150114)
			(end -0.299974 0.150114)
			(stroke
				(width 0.1)
				(type default)
			)
			(layer "F.Fab")
		)
		(fp_line
			(start 0.299974 -0.150114)
			(end 0.299974 0.150114)
			(stroke
				(width 0.1)
				(type default)
			)
			(layer "F.Fab")
		)
		(fp_line
			(start -0.299974 0.150114)
			(end -0.299974 -0.150114)
			(stroke
				(width 0.1)
				(type default)
			)
			(layer "F.Fab")
		)
		(fp_line
			(start -0.299974 -0.150114)
			(end 0.299974 -0.150114)
			(stroke
				(width 0.1)
				(type default)
			)
			(layer "F.Fab")
		)
		(pad "1" smd rect
			(at -0.2667 0 180)
			(size 0.3048 0.381)
			(layers "F.Cu" "F.Mask" "F.Paste")
			(net "P5E_CPU0_P3_TX_C_DN<1>")
		)
		(pad "2" smd rect
			(at 0.2667 0 180)
			(size 0.3048 0.381)
			(layers "F.Cu" "F.Mask" "F.Paste")
			(net "P5E_CPU0_P3_TX_DN<1>")
		)
	)
	(footprint ""
		(layer "F.Cu")
		(at 33.291272 -434.173884)
		(property "Reference" "C1766"
			(at 0 0 0)
			(layer "F.SilkS")
			(hide yes)
			(effects
				(font
					(size 1.27 1.27)
				)
			)
		)
		(property "Value" ""
			(at 0 0 0)
			(layer "F.Fab")
			(effects
				(font
					(size 1.27 1.27)
				)
			)
		)
		(duplicate_pad_numbers_are_jumpers no)
		(fp_line
			(start -0.7874 -0.4064)
			(end 0.7874 -0.4064)
			(stroke
				(width 0.1524)
				(type default)
			)
			(layer "F.SilkS")
		)
		(fp_line
			(start -0.7874 0.4064)
			(end -0.7874 -0.4064)
			(stroke
				(width 0.1524)
				(type default)
			)
			(layer "F.SilkS")
		)
		(fp_line
			(start 0.7874 -0.4064)
			(end 0.7874 0.4064)
			(stroke
				(width 0.1524)
				(type default)
			)
			(layer "F.SilkS")
		)
		(fp_line
			(start 0.7874 0.4064)
			(end -0.7874 0.4064)
			(stroke
				(width 0.1524)
				(type default)
			)
			(layer "F.SilkS")
		)
		(fp_line
			(start -0.67945 -0.305054)
			(end -0.12065 -0.305054)
			(stroke
				(width 0.1)
				(type default)
			)
			(layer "F.Fab")
		)
		(fp_line
			(start -0.67945 0.3048)
			(end -0.67945 -0.305054)
			(stroke
				(width 0.1)
				(type default)
			)
			(layer "F.Fab")
		)
		(fp_line
			(start -0.12065 -0.305054)
			(end -0.12065 -0.2794)
			(stroke
				(width 0.1)
				(type default)
			)
			(layer "F.Fab")
		)
		(fp_line
			(start -0.12065 -0.2794)
			(end 0.12065 -0.2794)
			(stroke
				(width 0.1)
				(type default)
			)
			(layer "F.Fab")
		)
		(fp_line
			(start -0.12065 0.2794)
			(end -0.12065 0.3048)
			(stroke
				(width 0.1)
				(type default)
			)
			(layer "F.Fab")
		)
		(fp_line
			(start -0.12065 0.3048)
			(end -0.67945 0.3048)
			(stroke
				(width 0.1)
				(type default)
			)
			(layer "F.Fab")
		)
		(fp_line
			(start 0.120396 0.2794)
			(end -0.12065 0.2794)
			(stroke
				(width 0.1)
				(type default)
			)
			(layer "F.Fab")
		)
		(fp_line
			(start 0.120396 0.3048)
			(end 0.120396 0.2794)
			(stroke
				(width 0.1)
				(type default)
			)
			(layer "F.Fab")
		)
		(fp_line
			(start 0.12065 -0.3048)
			(end 0.67945 -0.3048)
			(stroke
				(width 0.1)
				(type default)
			)
			(layer "F.Fab")
		)
		(fp_line
			(start 0.12065 -0.2794)
			(end 0.12065 -0.3048)
			(stroke
				(width 0.1)
				(type default)
			)
			(layer "F.Fab")
		)
		(fp_line
			(start 0.67945 -0.3048)
			(end 0.67945 0.3048)
			(stroke
				(width 0.1)
				(type default)
			)
			(layer "F.Fab")
		)
		(fp_line
			(start 0.67945 0.3048)
			(end 0.120396 0.3048)
			(stroke
				(width 0.1)
				(type default)
			)
			(layer "F.Fab")
		)
		(pad "1" smd circle
			(at -0.40005 0)
			(size 0 0)
			(layers "F.Cu" "F.Mask" "F.Paste")
			(net "P3V3_AUX")
		)
		(pad "2" smd circle
			(at 0.40005 0)
			(size 0 0)
			(layers "F.Cu" "F.Mask" "F.Paste")
			(net "GND")
		)
	)
)
